(kicad_pcb
	(version 20260206)
	(generator "pcbnew")
	(generator_version "10.0")
	(general
		(thickness 1.6)
		(legacy_teardrops no)
	)
	(paper "A4")
	(title_block
		(title "12092022_DA0F0TMDCD0_F0T_Management_Board_D_brd_V3_OCP.brd")
		(comment 1 "Grand Teton / footprints 1093-1098 of 1440")
	)
	(layers
		(0 "F.Cu" signal "TOP")
		(4 "In1.Cu" signal "GND")
		(6 "In2.Cu" signal "IN1")
		(8 "In3.Cu" signal "GND1")
		(10 "In4.Cu" signal "IN2")
		(12 "In5.Cu" signal "VCC")
		(14 "In6.Cu" signal "VCC1")
		(16 "In7.Cu" signal "IN3")
		(18 "In8.Cu" signal "GND2")
		(20 "In9.Cu" signal "IN4")
		(22 "In10.Cu" signal "GND3")
		(2 "B.Cu" signal "BOTTOM")
		(9 "F.Adhes" user "F.Adhesive")
		(11 "B.Adhes" user "B.Adhesive")
		(13 "F.Paste" user "Package Geometry/Pastemask Top")
		(15 "B.Paste" user "Package Geometry/Pastemask Bottom")
		(5 "F.SilkS" user "Ref Des/Silkscreen Top")
		(7 "B.SilkS" user "Ref Des/Silkscreen Bottom")
		(1 "F.Mask" user "Board Geometry/Soldermask Top")
		(3 "B.Mask" user "Board Geometry/Soldermask Bottom")
		(17 "Dwgs.User" user "User.Drawings")
		(19 "Cmts.User" user "User.Comments")
		(21 "Eco1.User" user "User.Eco1")
		(23 "Eco2.User" user "User.Eco2")
		(25 "Edge.Cuts" user "Board Geometry/Outline")
		(27 "Margin" user)
		(31 "F.CrtYd" user "Package Geometry/Place Bound Top")
		(29 "B.CrtYd" user "Package Geometry/Place Bound Bottom")
		(35 "F.Fab" user "Ref Des/Assembly Top")
		(33 "B.Fab" user "Ref Des/Assembly Bottom")
	)
	(footprint ""
		(layer "B.Cu")
		(at 66.127884 -30.740604 -90)
		(property "Reference" "R211"
			(at 0 0 90)
			(layer "B.SilkS")
			(hide yes)
			(effects
				(font
					(size 1.27 1.27)
				)
				(justify mirror)
			)
		)
		(property "Value" ""
			(at 0 0 90)
			(layer "B.Fab")
			(effects
				(font
					(size 1.27 1.27)
				)
				(justify mirror)
			)
		)
		(duplicate_pad_numbers_are_jumpers no)
		(fp_line
			(start -0.7874 0.4064)
			(end 0.7874 0.4064)
			(stroke
				(width 0.1524)
				(type default)
			)
			(layer "B.SilkS")
		)
		(fp_line
			(start 0.7874 0.4064)
			(end 0.7874 -0.4064)
			(stroke
				(width 0.1524)
				(type default)
			)
			(layer "B.SilkS")
		)
		(fp_line
			(start -0.7874 -0.4064)
			(end -0.7874 0.4064)
			(stroke
				(width 0.1524)
				(type default)
			)
			(layer "B.SilkS")
		)
		(fp_line
			(start 0.7874 -0.4064)
			(end -0.7874 -0.4064)
			(stroke
				(width 0.1524)
				(type default)
			)
			(layer "B.SilkS")
		)
		(fp_line
			(start -0.67945 0.3048)
			(end -0.120396 0.3048)
			(stroke
				(width 0.1)
				(type default)
			)
			(layer "B.Fab")
		)
		(fp_line
			(start -0.120396 0.3048)
			(end -0.120396 0.2794)
			(stroke
				(width 0.1)
				(type default)
			)
			(layer "B.Fab")
		)
		(fp_line
			(start 0.12065 0.3048)
			(end 0.67945 0.3048)
			(stroke
				(width 0.1)
				(type default)
			)
			(layer "B.Fab")
		)
		(fp_line
			(start 0.67945 0.3048)
			(end 0.67945 -0.305054)
			(stroke
				(width 0.1)
				(type default)
			)
			(layer "B.Fab")
		)
		(fp_line
			(start -0.120396 0.2794)
			(end 0.12065 0.2794)
			(stroke
				(width 0.1)
				(type default)
			)
			(layer "B.Fab")
		)
		(fp_line
			(start 0.12065 0.2794)
			(end 0.12065 0.3048)
			(stroke
				(width 0.1)
				(type default)
			)
			(layer "B.Fab")
		)
		(fp_line
			(start -0.12065 -0.2794)
			(end -0.12065 -0.3048)
			(stroke
				(width 0.1)
				(type default)
			)
			(layer "B.Fab")
		)
		(fp_line
			(start 0.12065 -0.2794)
			(end -0.12065 -0.2794)
			(stroke
				(width 0.1)
				(type default)
			)
			(layer "B.Fab")
		)
		(fp_line
			(start -0.67945 -0.3048)
			(end -0.67945 0.3048)
			(stroke
				(width 0.1)
				(type default)
			)
			(layer "B.Fab")
		)
		(fp_line
			(start -0.12065 -0.3048)
			(end -0.67945 -0.3048)
			(stroke
				(width 0.1)
				(type default)
			)
			(layer "B.Fab")
		)
		(fp_line
			(start 0.12065 -0.305054)
			(end 0.12065 -0.2794)
			(stroke
				(width 0.1)
				(type default)
			)
			(layer "B.Fab")
		)
		(fp_line
			(start 0.67945 -0.305054)
			(end 0.12065 -0.305054)
			(stroke
				(width 0.1)
				(type default)
			)
			(layer "B.Fab")
		)
		(pad "1" smd circle
			(at 0.40005 0 90)
			(size 0 0)
			(layers "B.Cu" "B.Mask" "B.Paste")
			(net "P3V3_RGM")
		)
		(pad "2" smd circle
			(at -0.40005 0 90)
			(size 0 0)
			(layers "B.Cu" "B.Mask" "B.Paste")
			(net "FM_BMC_SSPRST_N")
		)
	)
	(footprint ""
		(layer "B.Cu")
		(at 56.904636 -54.898544 180)
		(property "Reference" "C102"
			(at 0 0 0)
			(layer "B.SilkS")
			(hide yes)
			(effects
				(font
					(size 1.27 1.27)
				)
				(justify mirror)
			)
		)
		(property "Value" ""
			(at 0 0 0)
			(layer "B.Fab")
			(effects
				(font
					(size 1.27 1.27)
				)
				(justify mirror)
			)
		)
		(duplicate_pad_numbers_are_jumpers no)
		(fp_line
			(start 0.7874 0.4064)
			(end 0.7874 -0.4064)
			(stroke
				(width 0.1524)
				(type default)
			)
			(layer "B.SilkS")
		)
		(fp_line
			(start 0.7874 -0.4064)
			(end -0.7874 -0.4064)
			(stroke
				(width 0.1524)
				(type default)
			)
			(layer "B.SilkS")
		)
		(fp_line
			(start -0.7874 0.4064)
			(end 0.7874 0.4064)
			(stroke
				(width 0.1524)
				(type default)
			)
			(layer "B.SilkS")
		)
		(fp_line
			(start -0.7874 -0.4064)
			(end -0.7874 0.4064)
			(stroke
				(width 0.1524)
				(type default)
			)
			(layer "B.SilkS")
		)
		(fp_line
			(start 0.67945 0.3048)
			(end 0.67945 -0.305054)
			(stroke
				(width 0.1)
				(type default)
			)
			(layer "B.Fab")
		)
		(fp_line
			(start 0.67945 -0.305054)
			(end 0.12065 -0.305054)
			(stroke
				(width 0.1)
				(type default)
			)
			(layer "B.Fab")
		)
		(fp_line
			(start 0.12065 0.3048)
			(end 0.67945 0.3048)
			(stroke
				(width 0.1)
				(type default)
			)
			(layer "B.Fab")
		)
		(fp_line
			(start 0.12065 0.2794)
			(end 0.12065 0.3048)
			(stroke
				(width 0.1)
				(type default)
			)
			(layer "B.Fab")
		)
		(fp_line
			(start 0.12065 -0.2794)
			(end -0.12065 -0.2794)
			(stroke
				(width 0.1)
				(type default)
			)
			(layer "B.Fab")
		)
		(fp_line
			(start 0.12065 -0.305054)
			(end 0.12065 -0.2794)
			(stroke
				(width 0.1)
				(type default)
			)
			(layer "B.Fab")
		)
		(fp_line
			(start -0.120396 0.3048)
			(end -0.120396 0.2794)
			(stroke
				(width 0.1)
				(type default)
			)
			(layer "B.Fab")
		)
		(fp_line
			(start -0.120396 0.2794)
			(end 0.12065 0.2794)
			(stroke
				(width 0.1)
				(type default)
			)
			(layer "B.Fab")
		)
		(fp_line
			(start -0.12065 -0.2794)
			(end -0.12065 -0.3048)
			(stroke
				(width 0.1)
				(type default)
			)
			(layer "B.Fab")
		)
		(fp_line
			(start -0.12065 -0.3048)
			(end -0.67945 -0.3048)
			(stroke
				(width 0.1)
				(type default)
			)
			(layer "B.Fab")
		)
		(fp_line
			(start -0.67945 0.3048)
			(end -0.120396 0.3048)
			(stroke
				(width 0.1)
				(type default)
			)
			(layer "B.Fab")
		)
		(fp_line
			(start -0.67945 -0.3048)
			(end -0.67945 0.3048)
			(stroke
				(width 0.1)
				(type default)
			)
			(layer "B.Fab")
		)
		(pad "1" smd circle
			(at 0.40005 0)
			(size 0 0)
			(layers "B.Cu" "B.Mask" "B.Paste")
			(net "P1V8_AUX")
		)
		(pad "2" smd circle
			(at -0.40005 0)
			(size 0 0)
			(layers "B.Cu" "B.Mask" "B.Paste")
			(net "GND")
		)
	)
	(footprint ""
		(layer "B.Cu")
		(at 42.346118 -34.637726 90)
		(property "Reference" "R165"
			(at 0 0 90)
			(layer "B.SilkS")
			(hide yes)
			(effects
				(font
					(size 1.27 1.27)
				)
				(justify mirror)
			)
		)
		(property "Value" ""
			(at 0 0 90)
			(layer "B.Fab")
			(effects
				(font
					(size 1.27 1.27)
				)
				(justify mirror)
			)
		)
		(duplicate_pad_numbers_are_jumpers no)
		(fp_line
			(start 0.7874 -0.4064)
			(end -0.7874 -0.4064)
			(stroke
				(width 0.1524)
				(type default)
			)
			(layer "B.SilkS")
		)
		(fp_line
			(start -0.7874 -0.4064)
			(end -0.7874 0.4064)
			(stroke
				(width 0.1524)
				(type default)
			)
			(layer "B.SilkS")
		)
		(fp_line
			(start 0.7874 0.4064)
			(end 0.7874 -0.4064)
			(stroke
				(width 0.1524)
				(type default)
			)
			(layer "B.SilkS")
		)
		(fp_line
			(start -0.7874 0.4064)
			(end 0.7874 0.4064)
			(stroke
				(width 0.1524)
				(type default)
			)
			(layer "B.SilkS")
		)
		(fp_line
			(start 0.67945 -0.305054)
			(end 0.12065 -0.305054)
			(stroke
				(width 0.1)
				(type default)
			)
			(layer "B.Fab")
		)
		(fp_line
			(start 0.12065 -0.305054)
			(end 0.12065 -0.2794)
			(stroke
				(width 0.1)
				(type default)
			)
			(layer "B.Fab")
		)
		(fp_line
			(start -0.12065 -0.3048)
			(end -0.67945 -0.3048)
			(stroke
				(width 0.1)
				(type default)
			)
			(layer "B.Fab")
		)
		(fp_line
			(start -0.67945 -0.3048)
			(end -0.67945 0.3048)
			(stroke
				(width 0.1)
				(type default)
			)
			(layer "B.Fab")
		)
		(fp_line
			(start 0.12065 -0.2794)
			(end -0.12065 -0.2794)
			(stroke
				(width 0.1)
				(type default)
			)
			(layer "B.Fab")
		)
		(fp_line
			(start -0.12065 -0.2794)
			(end -0.12065 -0.3048)
			(stroke
				(width 0.1)
				(type default)
			)
			(layer "B.Fab")
		)
		(fp_line
			(start 0.12065 0.2794)
			(end 0.12065 0.3048)
			(stroke
				(width 0.1)
				(type default)
			)
			(layer "B.Fab")
		)
		(fp_line
			(start -0.120396 0.2794)
			(end 0.12065 0.2794)
			(stroke
				(width 0.1)
				(type default)
			)
			(layer "B.Fab")
		)
		(fp_line
			(start 0.67945 0.3048)
			(end 0.67945 -0.305054)
			(stroke
				(width 0.1)
				(type default)
			)
			(layer "B.Fab")
		)
		(fp_line
			(start 0.12065 0.3048)
			(end 0.67945 0.3048)
			(stroke
				(width 0.1)
				(type default)
			)
			(layer "B.Fab")
		)
		(fp_line
			(start -0.120396 0.3048)
			(end -0.120396 0.2794)
			(stroke
				(width 0.1)
				(type default)
			)
			(layer "B.Fab")
		)
		(fp_line
			(start -0.67945 0.3048)
			(end -0.120396 0.3048)
			(stroke
				(width 0.1)
				(type default)
			)
			(layer "B.Fab")
		)
		(pad "1" smd circle
			(at 0.40005 0 270)
			(size 0 0)
			(layers "B.Cu" "B.Mask" "B.Paste")
			(net "SMB_BMC_MM2_R_SCL")
		)
		(pad "2" smd circle
			(at -0.40005 0 270)
			(size 0 0)
			(layers "B.Cu" "B.Mask" "B.Paste")
			(net "SMB_BMC_MM2_SCL")
		)
	)
	(footprint ""
		(layer "B.Cu")
		(at 49.420018 -49.808638 -90)
		(property "Reference" "C70"
			(at 0 0 90)
			(layer "B.SilkS")
			(hide yes)
			(effects
				(font
					(size 1.27 1.27)
				)
				(justify mirror)
			)
		)
		(property "Value" ""
			(at 0 0 90)
			(layer "B.Fab")
			(effects
				(font
					(size 1.27 1.27)
				)
				(justify mirror)
			)
		)
		(duplicate_pad_numbers_are_jumpers no)
		(fp_line
			(start -0.7874 0.4064)
			(end 0.7874 0.4064)
			(stroke
				(width 0.1524)
				(type default)
			)
			(layer "B.SilkS")
		)
		(fp_line
			(start 0.7874 0.4064)
			(end 0.7874 -0.4064)
			(stroke
				(width 0.1524)
				(type default)
			)
			(layer "B.SilkS")
		)
		(fp_line
			(start -0.7874 -0.4064)
			(end -0.7874 0.4064)
			(stroke
				(width 0.1524)
				(type default)
			)
			(layer "B.SilkS")
		)
		(fp_line
			(start 0.7874 -0.4064)
			(end -0.7874 -0.4064)
			(stroke
				(width 0.1524)
				(type default)
			)
			(layer "B.SilkS")
		)
		(fp_line
			(start -0.67945 0.3048)
			(end -0.120396 0.3048)
			(stroke
				(width 0.1)
				(type default)
			)
			(layer "B.Fab")
		)
		(fp_line
			(start -0.120396 0.3048)
			(end -0.120396 0.2794)
			(stroke
				(width 0.1)
				(type default)
			)
			(layer "B.Fab")
		)
		(fp_line
			(start 0.12065 0.3048)
			(end 0.67945 0.3048)
			(stroke
				(width 0.1)
				(type default)
			)
			(layer "B.Fab")
		)
		(fp_line
			(start 0.67945 0.3048)
			(end 0.67945 -0.305054)
			(stroke
				(width 0.1)
				(type default)
			)
			(layer "B.Fab")
		)
		(fp_line
			(start -0.120396 0.2794)
			(end 0.12065 0.2794)
			(stroke
				(width 0.1)
				(type default)
			)
			(layer "B.Fab")
		)
		(fp_line
			(start 0.12065 0.2794)
			(end 0.12065 0.3048)
			(stroke
				(width 0.1)
				(type default)
			)
			(layer "B.Fab")
		)
		(fp_line
			(start -0.12065 -0.2794)
			(end -0.12065 -0.3048)
			(stroke
				(width 0.1)
				(type default)
			)
			(layer "B.Fab")
		)
		(fp_line
			(start 0.12065 -0.2794)
			(end -0.12065 -0.2794)
			(stroke
				(width 0.1)
				(type default)
			)
			(layer "B.Fab")
		)
		(fp_line
			(start -0.67945 -0.3048)
			(end -0.67945 0.3048)
			(stroke
				(width 0.1)
				(type default)
			)
			(layer "B.Fab")
		)
		(fp_line
			(start -0.12065 -0.3048)
			(end -0.67945 -0.3048)
			(stroke
				(width 0.1)
				(type default)
			)
			(layer "B.Fab")
		)
		(fp_line
			(start 0.12065 -0.305054)
			(end 0.12065 -0.2794)
			(stroke
				(width 0.1)
				(type default)
			)
			(layer "B.Fab")
		)
		(fp_line
			(start 0.67945 -0.305054)
			(end 0.12065 -0.305054)
			(stroke
				(width 0.1)
				(type default)
			)
			(layer "B.Fab")
		)
		(pad "1" smd circle
			(at 0.40005 0 90)
			(size 0 0)
			(layers "B.Cu" "B.Mask" "B.Paste")
			(net "P1V2_AUX")
		)
		(pad "2" smd circle
			(at -0.40005 0 90)
			(size 0 0)
			(layers "B.Cu" "B.Mask" "B.Paste")
			(net "GND")
		)
	)
	(footprint ""
		(layer "B.Cu")
		(at 81.28 -101.473 90)
		(property "Reference" "C329"
			(at 0 0 90)
			(layer "B.SilkS")
			(hide yes)
			(effects
				(font
					(size 1.27 1.27)
				)
				(justify mirror)
			)
		)
		(property "Value" ""
			(at 0 0 90)
			(layer "B.Fab")
			(effects
				(font
					(size 1.27 1.27)
				)
				(justify mirror)
			)
		)
		(duplicate_pad_numbers_are_jumpers no)
		(fp_line
			(start 1.524 -0.762)
			(end -1.524 -0.762)
			(stroke
				(width 0.1524)
				(type default)
			)
			(layer "B.SilkS")
		)
		(fp_line
			(start -1.524 -0.762)
			(end -1.524 0.762)
			(stroke
				(width 0.1524)
				(type default)
			)
			(layer "B.SilkS")
		)
		(fp_line
			(start 1.524 0.762)
			(end 1.524 -0.762)
			(stroke
				(width 0.1524)
				(type default)
			)
			(layer "B.SilkS")
		)
		(fp_line
			(start -1.524 0.762)
			(end 1.524 0.762)
			(stroke
				(width 0.1524)
				(type default)
			)
			(layer "B.SilkS")
		)
		(fp_line
			(start 1.1049 -0.724916)
			(end 1.1049 0.724916)
			(stroke
				(width 0.1)
				(type default)
			)
			(layer "B.Fab")
		)
		(fp_line
			(start -1.1049 -0.724916)
			(end 1.1049 -0.724916)
			(stroke
				(width 0.1)
				(type default)
			)
			(layer "B.Fab")
		)
		(fp_line
			(start 1.1049 0.724916)
			(end -1.1049 0.724916)
			(stroke
				(width 0.1)
				(type default)
			)
			(layer "B.Fab")
		)
		(fp_line
			(start -1.1049 0.724916)
			(end -1.1049 -0.724916)
			(stroke
				(width 0.1)
				(type default)
			)
			(layer "B.Fab")
		)
		(pad "1" smd rect
			(at 0.889 0 90)
			(size 1.016 1.27)
			(layers "B.Cu" "B.Mask" "B.Paste")
			(net "P12V_AUX")
		)
		(pad "2" smd rect
			(at -0.889 0 90)
			(size 1.016 1.27)
			(layers "B.Cu" "B.Mask" "B.Paste")
			(net "GND")
		)
	)
	(footprint ""
		(layer "B.Cu")
		(at 51.3715 -86.9315 180)
		(property "Reference" "R702"
			(at 0 0 0)
			(layer "B.SilkS")
			(hide yes)
			(effects
				(font
					(size 1.27 1.27)
				)
				(justify mirror)
			)
		)
		(property "Value" ""
			(at 0 0 0)
			(layer "B.Fab")
			(effects
				(font
					(size 1.27 1.27)
				)
				(justify mirror)
			)
		)
		(duplicate_pad_numbers_are_jumpers no)
		(fp_line
			(start 0.7874 0.4064)
			(end 0.7874 -0.4064)
			(stroke
				(width 0.1524)
				(type default)
			)
			(layer "B.SilkS")
		)
		(fp_line
			(start 0.7874 -0.4064)
			(end -0.7874 -0.4064)
			(stroke
				(width 0.1524)
				(type default)
			)
			(layer "B.SilkS")
		)
		(fp_line
			(start -0.7874 0.4064)
			(end 0.7874 0.4064)
			(stroke
				(width 0.1524)
				(type default)
			)
			(layer "B.SilkS")
		)
		(fp_line
			(start -0.7874 -0.4064)
			(end -0.7874 0.4064)
			(stroke
				(width 0.1524)
				(type default)
			)
			(layer "B.SilkS")
		)
		(fp_line
			(start 0.67945 0.3048)
			(end 0.67945 -0.305054)
			(stroke
				(width 0.1)
				(type default)
			)
			(layer "B.Fab")
		)
		(fp_line
			(start 0.67945 -0.305054)
			(end 0.12065 -0.305054)
			(stroke
				(width 0.1)
				(type default)
			)
			(layer "B.Fab")
		)
		(fp_line
			(start 0.12065 0.3048)
			(end 0.67945 0.3048)
			(stroke
				(width 0.1)
				(type default)
			)
			(layer "B.Fab")
		)
		(fp_line
			(start 0.12065 0.2794)
			(end 0.12065 0.3048)
			(stroke
				(width 0.1)
				(type default)
			)
			(layer "B.Fab")
		)
		(fp_line
			(start 0.12065 -0.2794)
			(end -0.12065 -0.2794)
			(stroke
				(width 0.1)
				(type default)
			)
			(layer "B.Fab")
		)
		(fp_line
			(start 0.12065 -0.305054)
			(end 0.12065 -0.2794)
			(stroke
				(width 0.1)
				(type default)
			)
			(layer "B.Fab")
		)
		(fp_line
			(start -0.120396 0.3048)
			(end -0.120396 0.2794)
			(stroke
				(width 0.1)
				(type default)
			)
			(layer "B.Fab")
		)
		(fp_line
			(start -0.120396 0.2794)
			(end 0.12065 0.2794)
			(stroke
				(width 0.1)
				(type default)
			)
			(layer "B.Fab")
		)
		(fp_line
			(start -0.12065 -0.2794)
			(end -0.12065 -0.3048)
			(stroke
				(width 0.1)
				(type default)
			)
			(layer "B.Fab")
		)
		(fp_line
			(start -0.12065 -0.3048)
			(end -0.67945 -0.3048)
			(stroke
				(width 0.1)
				(type default)
			)
			(layer "B.Fab")
		)
		(fp_line
			(start -0.67945 0.3048)
			(end -0.120396 0.3048)
			(stroke
				(width 0.1)
				(type default)
			)
			(layer "B.Fab")
		)
		(fp_line
			(start -0.67945 -0.3048)
			(end -0.67945 0.3048)
			(stroke
				(width 0.1)
				(type default)
			)
			(layer "B.Fab")
		)
		(pad "1" smd circle
			(at 0.40005 0)
			(size 0 0)
			(layers "B.Cu" "B.Mask" "B.Paste")
			(net "RST_PLTRST_N")
		)
		(pad "2" smd circle
			(at -0.40005 0)
			(size 0 0)
			(layers "B.Cu" "B.Mask" "B.Paste")
			(net "RST_PLTRST_R2_N")
		)
	)
)
